(kicad_pcb
	(version 20241229)
	(generator "pcbnew")
	(generator_version "9.0")
	(general
		(thickness 1.294)
		(legacy_teardrops no)
	)
	(paper "A3")
	(title_block
		(title "Kintex 410T devboard")
		(date "2024-04-03")
		(rev "1.1.2")
		(comment 9 "footprints 841-846 of 975")
	)
	(layers
		(0 "F.Cu" mixed)
		(4 "In1.Cu" power)
		(6 "In2.Cu" power)
		(8 "In3.Cu" mixed)
		(10 "In4.Cu" power)
		(12 "In5.Cu" mixed)
		(14 "In6.Cu" power)
		(16 "In7.Cu" mixed)
		(18 "In8.Cu" power)
		(2 "B.Cu" mixed)
		(9 "F.Adhes" user "F.Adhesive")
		(11 "B.Adhes" user "B.Adhesive")
		(13 "F.Paste" user)
		(15 "B.Paste" user)
		(5 "F.SilkS" user "F.Silkscreen")
		(7 "B.SilkS" user "B.Silkscreen")
		(1 "F.Mask" user)
		(3 "B.Mask" user)
		(17 "Dwgs.User" user "User.Drawings")
		(19 "Cmts.User" user "User.Comments")
		(21 "Eco1.User" user "User.Eco1")
		(23 "Eco2.User" user "User.Eco2")
		(25 "Edge.Cuts" user)
		(27 "Margin" user)
		(31 "F.CrtYd" user "F.Courtyard")
		(29 "B.CrtYd" user "B.Courtyard")
		(35 "F.Fab" user)
		(33 "B.Fab" user)
	)
	(footprint "antmicro-footprints:R_0402_1005Metric"
		(layer "B.Cu")
		(at 171.25 169.31 90)
		(descr "Resistor SMD 0402")
		(tags "resistor SMD 0402")
		(property "Reference" "R306"
			(at -0.765 0.45 270)
			(layer "B.SilkS")
			(effects
				(font
					(size 0.7 0.7)
					(thickness 0.15)
				)
				(justify left bottom mirror)
			)
		)
		(property "Value" "R_0R_0402"
			(at 0 -1.4 270)
			(layer "B.Fab")
			(effects
				(font
					(size 0.7 0.7)
					(thickness 0.15)
				)
				(justify left bottom mirror)
			)
		)
		(property "Description" "SMD Chip Resistor, Jumper, 0 ohm, 100 mW, 0402 [1005 Metric], Thick Film, General Purpose"
			(at 0 0 90)
			(layer "F.Fab")
			(hide yes)
			(effects
				(font
					(size 1.27 1.27)
					(thickness 0.15)
				)
			)
		)
		(property "Author" "Antmicro"
			(at 340.56 -1.94 0)
			(layer "B.Fab")
			(hide yes)
			(effects
				(font
					(size 1 1)
					(thickness 0.15)
				)
				(justify mirror)
			)
		)
		(property "Current" "1A"
			(at 340.56 -1.94 0)
			(layer "B.Fab")
			(hide yes)
			(effects
				(font
					(size 1 1)
					(thickness 0.15)
				)
				(justify mirror)
			)
		)
		(property "DNP" "DNP"
			(at 340.56 -1.94 0)
			(layer "B.Fab")
			(hide yes)
			(effects
				(font
					(size 1 1)
					(thickness 0.15)
				)
				(justify mirror)
			)
		)
		(property "License" "Apache-2.0"
			(at 340.56 -1.94 0)
			(layer "B.Fab")
			(hide yes)
			(effects
				(font
					(size 1 1)
					(thickness 0.15)
				)
				(justify mirror)
			)
		)
		(property "MPN" "ERJ2GE0R00X"
			(at 340.56 -1.94 0)
			(layer "B.Fab")
			(hide yes)
			(effects
				(font
					(size 1 1)
					(thickness 0.15)
				)
				(justify mirror)
			)
		)
		(property "Manufacturer" "Panasonic"
			(at 340.56 -1.94 0)
			(layer "B.Fab")
			(hide yes)
			(effects
				(font
					(size 1 1)
					(thickness 0.15)
				)
				(justify mirror)
			)
		)
		(property "Tolerance" ""
			(at 340.56 -1.94 0)
			(layer "B.Fab")
			(hide yes)
			(effects
				(font
					(size 1 1)
					(thickness 0.15)
				)
				(justify mirror)
			)
		)
		(property "Val" "0R"
			(at 340.56 -1.94 0)
			(layer "B.Fab")
			(hide yes)
			(effects
				(font
					(size 1 1)
					(thickness 0.15)
				)
				(justify mirror)
			)
		)
		(property "dnp" ""
			(at 340.56 -1.94 0)
			(layer "B.Fab")
			(hide yes)
			(effects
				(font
					(size 1 1)
					(thickness 0.15)
				)
				(justify mirror)
			)
		)
		(property "exclude_from_bom" ""
			(at 340.56 -1.94 0)
			(layer "B.Fab")
			(hide yes)
			(effects
				(font
					(size 1 1)
					(thickness 0.15)
				)
				(justify mirror)
			)
		)
		(sheetname "DC-DC Converters")
		(sheetfile "dc-dc.kicad_sch")
		(attr smd exclude_from_bom)
		(fp_rect
			(start -0.925 0.47)
			(end 0.925 -0.47)
			(stroke
				(width 0.05)
				(type default)
			)
			(fill no)
			(layer "B.CrtYd")
		)
		(fp_rect
			(start -0.5 0.25)
			(end 0.5 -0.25)
			(stroke
				(width 0.15)
				(type solid)
			)
			(fill no)
			(layer "B.Fab")
		)
		(pad "1" smd roundrect
			(at -0.48 0 90)
			(size 0.59 0.64)
			(layers "B.Cu" "B.Mask" "B.Paste")
			(roundrect_rratio 0.25)
			(net 958 "/DC-DC Converters/FB5")
			(pintype "passive")
		)
		(pad "2" smd roundrect
			(at 0.48 0 90)
			(size 0.59 0.64)
			(layers "B.Cu" "B.Mask" "B.Paste")
			(roundrect_rratio 0.25)
			(net 1219 "/DC-DC Converters/SENSE_3V3_1_P")
			(pintype "passive")
		)
	)
	(footprint "antmicro-footprints:R_0402_1005Metric"
		(layer "B.Cu")
		(at 165.8 183.7 -90)
		(descr "Resistor SMD 0402")
		(tags "resistor SMD 0402")
		(property "Reference" "R283"
			(at -3.625 -0.325 90)
			(layer "B.SilkS")
			(effects
				(font
					(size 0.7 0.7)
					(thickness 0.15)
				)
				(justify left bottom mirror)
			)
		)
		(property "Value" "R_47k_0402"
			(at 0 -1.4 90)
			(layer "B.Fab")
			(effects
				(font
					(size 0.7 0.7)
					(thickness 0.15)
				)
				(justify left bottom mirror)
			)
		)
		(property "Description" "SMD Chip Resistor, 47 kohm, ± 1%, 62.5 mW, 0402 [1005 Metric], Thick Film, General Purpose"
			(at 0 0 270)
			(layer "F.Fab")
			(hide yes)
			(effects
				(font
					(size 1.27 1.27)
					(thickness 0.15)
				)
			)
		)
		(property "Author" "Antmicro"
			(at -17.9 349.5 0)
			(layer "B.Fab")
			(hide yes)
			(effects
				(font
					(size 1 1)
					(thickness 0.15)
				)
				(justify mirror)
			)
		)
		(property "DNP" "DNP"
			(at -17.9 349.5 0)
			(layer "B.Fab")
			(hide yes)
			(effects
				(font
					(size 1 1)
					(thickness 0.15)
				)
				(justify mirror)
			)
		)
		(property "License" "Apache-2.0"
			(at -17.9 349.5 0)
			(layer "B.Fab")
			(hide yes)
			(effects
				(font
					(size 1 1)
					(thickness 0.15)
				)
				(justify mirror)
			)
		)
		(property "MPN" "CR0402-FX-4702GLF"
			(at -17.9 349.5 0)
			(layer "B.Fab")
			(hide yes)
			(effects
				(font
					(size 1 1)
					(thickness 0.15)
				)
				(justify mirror)
			)
		)
		(property "Manufacturer" "Bourns"
			(at -17.9 349.5 0)
			(layer "B.Fab")
			(hide yes)
			(effects
				(font
					(size 1 1)
					(thickness 0.15)
				)
				(justify mirror)
			)
		)
		(property "Tolerance" "1%"
			(at -17.9 349.5 0)
			(layer "B.Fab")
			(hide yes)
			(effects
				(font
					(size 1 1)
					(thickness 0.15)
				)
				(justify mirror)
			)
		)
		(property "Val" "47k"
			(at -17.9 349.5 0)
			(layer "B.Fab")
			(hide yes)
			(effects
				(font
					(size 1 1)
					(thickness 0.15)
				)
				(justify mirror)
			)
		)
		(property "dnp" ""
			(at -17.9 349.5 0)
			(layer "B.Fab")
			(hide yes)
			(effects
				(font
					(size 1 1)
					(thickness 0.15)
				)
				(justify mirror)
			)
		)
		(property "exclude_from_bom" ""
			(at -17.9 349.5 0)
			(layer "B.Fab")
			(hide yes)
			(effects
				(font
					(size 1 1)
					(thickness 0.15)
				)
				(justify mirror)
			)
		)
		(sheetname "DC-DC Converters")
		(sheetfile "dc-dc.kicad_sch")
		(attr smd exclude_from_bom)
		(fp_rect
			(start -0.925 0.47)
			(end 0.925 -0.47)
			(stroke
				(width 0.05)
				(type default)
			)
			(fill no)
			(layer "B.CrtYd")
		)
		(fp_rect
			(start -0.5 0.25)
			(end 0.5 -0.25)
			(stroke
				(width 0.15)
				(type solid)
			)
			(fill no)
			(layer "B.Fab")
		)
		(pad "1" smd roundrect
			(at -0.48 0 270)
			(size 0.59 0.64)
			(layers "B.Cu" "B.Mask" "B.Paste")
			(roundrect_rratio 0.25)
			(net 956 "/DC-DC Converters/POE_DC")
			(pintype "passive")
		)
		(pad "2" smd roundrect
			(at 0.48 0 270)
			(size 0.59 0.64)
			(layers "B.Cu" "B.Mask" "B.Paste")
			(roundrect_rratio 0.25)
			(net 797 "/DC-DC Converters/PB_CTRL_OE")
			(pintype "passive")
		)
	)
	(footprint "antmicro-footprints:R_0402_1005Metric"
		(layer "B.Cu")
		(at 165.1125 168.6 90)
		(descr "Resistor SMD 0402")
		(tags "resistor SMD 0402")
		(property "Reference" "R305"
			(at -0.725 0.4375 270)
			(layer "B.SilkS")
			(effects
				(font
					(size 0.7 0.7)
					(thickness 0.15)
				)
				(justify left bottom mirror)
			)
		)
		(property "Value" "R_0R_0402"
			(at 0 -1.4 270)
			(layer "B.Fab")
			(effects
				(font
					(size 0.7 0.7)
					(thickness 0.15)
				)
				(justify left bottom mirror)
			)
		)
		(property "Description" "SMD Chip Resistor, Jumper, 0 ohm, 100 mW, 0402 [1005 Metric], Thick Film, General Purpose"
			(at 0 0 90)
			(layer "F.Fab")
			(hide yes)
			(effects
				(font
					(size 1.27 1.27)
					(thickness 0.15)
				)
			)
		)
		(property "Author" "Antmicro"
			(at 333.7125 3.4875 0)
			(layer "B.Fab")
			(hide yes)
			(effects
				(font
					(size 1 1)
					(thickness 0.15)
				)
				(justify mirror)
			)
		)
		(property "Current" "1A"
			(at 333.7125 3.4875 0)
			(layer "B.Fab")
			(hide yes)
			(effects
				(font
					(size 1 1)
					(thickness 0.15)
				)
				(justify mirror)
			)
		)
		(property "DNP" "DNP"
			(at 333.7125 3.4875 0)
			(layer "B.Fab")
			(hide yes)
			(effects
				(font
					(size 1 1)
					(thickness 0.15)
				)
				(justify mirror)
			)
		)
		(property "License" "Apache-2.0"
			(at 333.7125 3.4875 0)
			(layer "B.Fab")
			(hide yes)
			(effects
				(font
					(size 1 1)
					(thickness 0.15)
				)
				(justify mirror)
			)
		)
		(property "MPN" "ERJ2GE0R00X"
			(at 333.7125 3.4875 0)
			(layer "B.Fab")
			(hide yes)
			(effects
				(font
					(size 1 1)
					(thickness 0.15)
				)
				(justify mirror)
			)
		)
		(property "Manufacturer" "Panasonic"
			(at 333.7125 3.4875 0)
			(layer "B.Fab")
			(hide yes)
			(effects
				(font
					(size 1 1)
					(thickness 0.15)
				)
				(justify mirror)
			)
		)
		(property "Tolerance" ""
			(at 333.7125 3.4875 0)
			(layer "B.Fab")
			(hide yes)
			(effects
				(font
					(size 1 1)
					(thickness 0.15)
				)
				(justify mirror)
			)
		)
		(property "Val" "0R"
			(at 333.7125 3.4875 0)
			(layer "B.Fab")
			(hide yes)
			(effects
				(font
					(size 1 1)
					(thickness 0.15)
				)
				(justify mirror)
			)
		)
		(property "dnp" ""
			(at 333.7125 3.4875 0)
			(layer "B.Fab")
			(hide yes)
			(effects
				(font
					(size 1 1)
					(thickness 0.15)
				)
				(justify mirror)
			)
		)
		(property "exclude_from_bom" ""
			(at 333.7125 3.4875 0)
			(layer "B.Fab")
			(hide yes)
			(effects
				(font
					(size 1 1)
					(thickness 0.15)
				)
				(justify mirror)
			)
		)
		(sheetname "DC-DC Converters")
		(sheetfile "dc-dc.kicad_sch")
		(attr smd exclude_from_bom)
		(fp_rect
			(start -0.925 0.47)
			(end 0.925 -0.47)
			(stroke
				(width 0.05)
				(type default)
			)
			(fill no)
			(layer "B.CrtYd")
		)
		(fp_rect
			(start -0.5 0.25)
			(end 0.5 -0.25)
			(stroke
				(width 0.15)
				(type solid)
			)
			(fill no)
			(layer "B.Fab")
		)
		(pad "1" smd roundrect
			(at -0.48 0 90)
			(size 0.59 0.64)
			(layers "B.Cu" "B.Mask" "B.Paste")
			(roundrect_rratio 0.25)
			(net 960 "/DC-DC Converters/FB2")
			(pintype "passive")
		)
		(pad "2" smd roundrect
			(at 0.48 0 90)
			(size 0.59 0.64)
			(layers "B.Cu" "B.Mask" "B.Paste")
			(roundrect_rratio 0.25)
			(net 1224 "/DC-DC Converters/SENSE_1V8_P")
			(pintype "passive")
		)
	)
	(footprint "antmicro-footprints:C_0201"
		(layer "B.Cu")
		(at 201.5 130.45)
		(descr "Capacitor SMD 0201")
		(tags "capacitor SMD 0201")
		(property "Reference" "C50"
			(at 24.7 -28.75 0)
			(layer "B.SilkS")
			(effects
				(font
					(size 0.7 0.7)
					(thickness 0.15)
				)
				(justify right bottom mirror)
			)
		)
		(property "Value" "C_4u7_0201"
			(at 0 -1.4 0)
			(layer "B.Fab")
			(effects
				(font
					(size 0.7 0.7)
					(thickness 0.15)
				)
				(justify right bottom mirror)
			)
		)
		(property "Description" "SMD Multilayer Ceramic Capacitor, 4.7 µF, 6.3 V, 0201 [0603 Metric], ± 20%, X5R, GRM Series"
			(at 0 0 0)
			(layer "F.Fab")
			(hide yes)
			(effects
				(font
					(size 1.27 1.27)
					(thickness 0.15)
				)
			)
		)
		(property "Author" "Antmicro"
			(at 0 0 0)
			(layer "B.Fab")
			(hide yes)
			(effects
				(font
					(size 1 1)
					(thickness 0.15)
				)
				(justify mirror)
			)
		)
		(property "Dielectric" ""
			(at 0 0 0)
			(layer "B.Fab")
			(hide yes)
			(effects
				(font
					(size 1 1)
					(thickness 0.15)
				)
				(justify mirror)
			)
		)
		(property "License" "Apache-2.0"
			(at 0 0 0)
			(layer "B.Fab")
			(hide yes)
			(effects
				(font
					(size 1 1)
					(thickness 0.15)
				)
				(justify mirror)
			)
		)
		(property "MPN" "GRM035R60J475ME15D"
			(at 0 0 0)
			(layer "B.Fab")
			(hide yes)
			(effects
				(font
					(size 1 1)
					(thickness 0.15)
				)
				(justify mirror)
			)
		)
		(property "Manufacturer" "Murata"
			(at 0 0 0)
			(layer "B.Fab")
			(hide yes)
			(effects
				(font
					(size 1 1)
					(thickness 0.15)
				)
				(justify mirror)
			)
		)
		(property "Val" "4u7"
			(at 0 0 0)
			(layer "B.Fab")
			(hide yes)
			(effects
				(font
					(size 1 1)
					(thickness 0.15)
				)
				(justify mirror)
			)
		)
		(property "Voltage" ""
			(at 0 0 0)
			(layer "B.Fab")
			(hide yes)
			(effects
				(font
					(size 1 1)
					(thickness 0.15)
				)
				(justify mirror)
			)
		)
		(sheetname "FPGA supply")
		(sheetfile "fpga-supply.kicad_sch")
		(attr smd)
		(fp_rect
			(start -0.7 0.35)
			(end 0.7 -0.35)
			(stroke
				(width 0.05)
				(type default)
			)
			(fill no)
			(layer "B.CrtYd")
		)
		(fp_rect
			(start 0.3 -0.15)
			(end -0.301 0.149)
			(stroke
				(width 0.15)
				(type solid)
			)
			(fill no)
			(layer "B.Fab")
		)
		(pad "" smd roundrect
			(at -0.349 0.002)
			(size 0.318 0.36)
			(layers "B.Paste")
			(roundrect_rratio 0.25)
		)
		(pad "" smd roundrect
			(at 0.341 0.002)
			(size 0.318 0.36)
			(layers "B.Paste")
			(roundrect_rratio 0.25)
		)
		(pad "1" smd roundrect
			(at -0.321 0.002)
			(size 0.46 0.4)
			(layers "B.Cu" "B.Mask")
			(roundrect_rratio 0.25)
			(net 1 "GND")
			(pintype "passive")
		)
		(pad "2" smd roundrect
			(at 0.32 0.002)
			(size 0.46 0.4)
			(layers "B.Cu" "B.Mask")
			(roundrect_rratio 0.25)
			(net 650 "+1V0")
			(pintype "passive")
		)
	)
	(footprint "antmicro-footprints:R_0402_1005Metric"
		(layer "B.Cu")
		(at 223.586 148.2 180)
		(descr "Resistor SMD 0402")
		(tags "resistor SMD 0402")
		(property "Reference" "R221"
			(at -1.839 -2.35 0)
			(layer "B.SilkS")
			(effects
				(font
					(size 0.7 0.7)
					(thickness 0.15)
				)
				(justify left bottom mirror)
			)
		)
		(property "Value" "R_10k_0402"
			(at 0 -1.4 0)
			(layer "B.Fab")
			(effects
				(font
					(size 0.7 0.7)
					(thickness 0.15)
				)
				(justify left bottom mirror)
			)
		)
		(property "Description" "SMD Chip Resistor, 10 kohm, ± 1%, 62.5 mW, 0402 [1005 Metric], Thick Film, General Purpose"
			(at 0 0 180)
			(layer "F.Fab")
			(hide yes)
			(effects
				(font
					(size 1.27 1.27)
					(thickness 0.15)
				)
			)
		)
		(property "Author" "Antmicro"
			(at 447.172 296.4 0)
			(layer "B.Fab")
			(hide yes)
			(effects
				(font
					(size 1 1)
					(thickness 0.15)
				)
				(justify mirror)
			)
		)
		(property "License" "Apache-2.0"
			(at 447.172 296.4 0)
			(layer "B.Fab")
			(hide yes)
			(effects
				(font
					(size 1 1)
					(thickness 0.15)
				)
				(justify mirror)
			)
		)
		(property "MPN" "CR0402-FX-1002GLF"
			(at 447.172 296.4 0)
			(layer "B.Fab")
			(hide yes)
			(effects
				(font
					(size 1 1)
					(thickness 0.15)
				)
				(justify mirror)
			)
		)
		(property "Manufacturer" "Bourns"
			(at 447.172 296.4 0)
			(layer "B.Fab")
			(hide yes)
			(effects
				(font
					(size 1 1)
					(thickness 0.15)
				)
				(justify mirror)
			)
		)
		(property "Tolerance" "1%"
			(at 447.172 296.4 0)
			(layer "B.Fab")
			(hide yes)
			(effects
				(font
					(size 1 1)
					(thickness 0.15)
				)
				(justify mirror)
			)
		)
		(property "Val" "10k"
			(at 447.172 296.4 0)
			(layer "B.Fab")
			(hide yes)
			(effects
				(font
					(size 1 1)
					(thickness 0.15)
				)
				(justify mirror)
			)
		)
		(sheetname "HDMI + Ethernet")
		(sheetfile "hdmi-ethernet.kicad_sch")
		(attr smd)
		(fp_rect
			(start -0.925 0.47)
			(end 0.925 -0.47)
			(stroke
				(width 0.05)
				(type default)
			)
			(fill no)
			(layer "B.CrtYd")
		)
		(fp_rect
			(start -0.5 0.25)
			(end 0.5 -0.25)
			(stroke
				(width 0.15)
				(type solid)
			)
			(fill no)
			(layer "B.Fab")
		)
		(pad "1" smd roundrect
			(at -0.48 0 180)
			(size 0.59 0.64)
			(layers "B.Cu" "B.Mask" "B.Paste")
			(roundrect_rratio 0.25)
			(net 946 "/HDMI + Ethernet/ETH_PHY_RXDO")
			(pintype "passive")
		)
		(pad "2" smd roundrect
			(at 0.48 0 180)
			(size 0.59 0.64)
			(layers "B.Cu" "B.Mask" "B.Paste")
			(roundrect_rratio 0.25)
			(net 26 "+1V8")
			(pintype "passive")
		)
	)
	(footprint "antmicro-footprints:R_0402_1005Metric"
		(layer "B.Cu")
		(at 258.4 86.2 -90)
		(descr "Resistor SMD 0402")
		(tags "resistor SMD 0402")
		(property "Reference" "R354"
			(at -1.225 0.475 90)
			(layer "B.SilkS")
			(effects
				(font
					(size 0.7 0.7)
					(thickness 0.15)
				)
				(justify left bottom mirror)
			)
		)
		(property "Value" "R_100k_0402"
			(at 0 -1.4 90)
			(layer "B.Fab")
			(effects
				(font
					(size 0.7 0.7)
					(thickness 0.15)
				)
				(justify left bottom mirror)
			)
		)
		(property "Description" "SMD Chip Resistor, 100 kohm, ± 1%, 62.5 mW, 0402 [1005 Metric], Thick Film, General Purpose"
			(at 0 0 270)
			(layer "F.Fab")
			(hide yes)
			(effects
				(font
					(size 1.27 1.27)
					(thickness 0.15)
				)
			)
		)
		(property "Author" "Antmicro"
			(at 172.2 344.6 0)
			(layer "B.Fab")
			(hide yes)
			(effects
				(font
					(size 1 1)
					(thickness 0.15)
				)
				(justify mirror)
			)
		)
		(property "License" "Apache-2.0"
			(at 172.2 344.6 0)
			(layer "B.Fab")
			(hide yes)
			(effects
				(font
					(size 1 1)
					(thickness 0.15)
				)
				(justify mirror)
			)
		)
		(property "MPN" "CR0402-FX-1003GLF"
			(at 172.2 344.6 0)
			(layer "B.Fab")
			(hide yes)
			(effects
				(font
					(size 1 1)
					(thickness 0.15)
				)
				(justify mirror)
			)
		)
		(property "Manufacturer" "Bourns"
			(at 172.2 344.6 0)
			(layer "B.Fab")
			(hide yes)
			(effects
				(font
					(size 1 1)
					(thickness 0.15)
				)
				(justify mirror)
			)
		)
		(property "Tolerance" "1%"
			(at 172.2 344.6 0)
			(layer "B.Fab")
			(hide yes)
			(effects
				(font
					(size 1 1)
					(thickness 0.15)
				)
				(justify mirror)
			)
		)
		(property "Val" "100k"
			(at 172.2 344.6 0)
			(layer "B.Fab")
			(hide yes)
			(effects
				(font
					(size 1 1)
					(thickness 0.15)
				)
				(justify mirror)
			)
		)
		(sheetname "User GPIO + LED + button + DIP switch")
		(sheetfile "user-gpio.kicad_sch")
		(attr smd)
		(fp_rect
			(start -0.925 0.47)
			(end 0.925 -0.47)
			(stroke
				(width 0.05)
				(type default)
			)
			(fill no)
			(layer "B.CrtYd")
		)
		(fp_rect
			(start -0.5 0.25)
			(end 0.5 -0.25)
			(stroke
				(width 0.15)
				(type solid)
			)
			(fill no)
			(layer "B.Fab")
		)
		(pad "1" smd roundrect
			(at -0.48 0 270)
			(size 0.59 0.64)
			(layers "B.Cu" "B.Mask" "B.Paste")
			(roundrect_rratio 0.25)
			(net 1300 "/USER_IO.LED_GREEN1")
			(pintype "passive")
		)
		(pad "2" smd roundrect
			(at 0.48 0 270)
			(size 0.59 0.64)
			(layers "B.Cu" "B.Mask" "B.Paste")
			(roundrect_rratio 0.25)
			(net 1 "GND")
			(pintype "passive")
		)
	)
)
